#ISCELL
  mstr_misc dns *
  *
#ISCELL
  pure_quanta quanta_title_block_c *
  *
#CELL
  pure_quanta q_cap *
  page329_i1
#ISCELL
  logical_power universal_gnd *
  page329_i10
#CELL
  pure_quanta q_cap *
  page329_i11
#CELL
  pure_quanta ap331awg7 *
  page329_i12
#ISCELL
  logical_power universal_gnd *
  page329_i13
#CELL
  pure_quanta q_cap *
  page329_i14
#ISCELL
  logical_power universal_gnd *
  page329_i15
#ISCELL
  logical_power universal_power *
  page329_i16
#CELL
  pure_quanta q_res *
  page329_i17
#ISCELL
  logical_power universal_gnd *
  page329_i18
#ISCELL
  logical_power universal_gnd *
  page329_i19
#CELL
  pure_quanta q_res *
  page329_i2
#ISCELL
  logical_power universal_power *
  page329_i20
#CELL
  pure_quanta q_res *
  page329_i21
#ISCELL
  logical_power universal_gnd *
  page329_i22
#CELL
  pure_quanta ap331awg7 *
  page329_i23
#ISCELL
  logical_power universal_power *
  page329_i24
#CELL
  pure_quanta q_res *
  page329_i25
#ISCELL
  standard offpage *
  page329_i26
#CELL
  pure_quanta q_res *
  page329_i27
#ISCELL
  logical_power universal_gnd *
  page329_i28
#CELL
  pure_quanta q_cap *
  page329_i29
#CELL
  pure_quanta lm4040aim3x25nopb *
  page329_i3
#ISCELL
  logical_power universal_power *
  page329_i30
#CELL
  pure_quanta q_res *
  page329_i31
#ISCELL
  logical_power universal_gnd *
  page329_i32
#CELL
  pure_quanta q_cap *
  page329_i33
#ISCELL
  logical_power universal_gnd *
  page329_i34
#CELL
  pure_quanta q_cap *
  page329_i35
#ISCELL
  logical_power universal_gnd *
  page329_i36
#ISCELL
  logical_power universal_power *
  page329_i37
#CELL
  pure_quanta q_res *
  page329_i38
#CELL
  pure_quanta q_res *
  page329_i39
#ISCELL
  logical_power universal_power *
  page329_i4
#ISCELL
  logical_power universal_gnd *
  page329_i40
#ISCELL
  logical_power universal_power *
  page329_i41
#CELL
  pure_quanta q_res *
  page329_i42
#CELL
  pure_quanta lm4040aim3x25nopb *
  page329_i43
#ISCELL
  logical_power universal_gnd *
  page329_i44
#CELL
  pure_quanta ap331awg7 *
  page329_i45
#CELL
  pure_quanta q_res *
  page329_i46
#ISCELL
  logical_power universal_power *
  page329_i47
#ISCELL
  standard offpage *
  page329_i48
#CELL
  pure_quanta q_res *
  page329_i49
#ISCELL
  standard offpage *
  page329_i5
#CELL
  pure_quanta q_res *
  page329_i50
#CELL
  pure_quanta q_cap *
  page329_i51
#ISCELL
  logical_power universal_power *
  page329_i52
#ISCELL
  logical_power universal_gnd *
  page329_i53
#ISCELL
  logical_power universal_gnd *
  page329_i54
#CELL
  pure_quanta q_cap *
  page329_i55
#ISCELL
  logical_power universal_gnd *
  page329_i56
#CELL
  pure_quanta q_cap *
  page329_i57
#ISCELL
  logical_power universal_gnd *
  page329_i58
#ISCELL
  logical_power universal_power *
  page329_i59
#CELL
  pure_quanta q_res *
  page329_i6
#ISCELL
  logical_power universal_gnd *
  page329_i62
#CELL
  pure_quanta lm4040aim3x25nopb *
  page329_i63
#ISCELL
  logical_power universal_power *
  page329_i64
#CELL
  pure_quanta q_res *
  page329_i65
#ISCELL
  logical_power universal_gnd *
  page329_i66
#CELL
  pure_quanta q_res *
  page329_i67
#CELL
  pure_quanta q_res *
  page329_i68
#CELL
  pure_quanta q_res *
  page329_i7
#ISCELL
  logical_power universal_power *
  page329_i8
#CELL
  pure_quanta q_res *
  page329_i9
